# BASEBOARD_FAB2 (Tioga Pass) — schematic netlist excerpt (pin names and nets, part order shuffled) for the footprints in the layout excerpt that follows; sources: Cadence DE-HDL packaged netlist, KiCad conversion of Wiwynn_Tioga_Pass_MB.brd

R3N7  RES  0.0 5% CHIP  pkg 0402  page 212 : A = VR_PVCCIO_CPU0_PH1_VCIN ; B = P5V_STBY
C5P42  CAP  100UF 4V 20% X5R  pkg 0805  page 217 : A = PVDDQ_ABC ; B = GND
R1M5  RES  0.0 5% CHIP  pkg 0402  page 176 : A = USB2_P01_DP ; B = USB2_P01_ESD_DP

(kicad_pcb
	(version 20260206)
	(generator "pcbnew")
	(generator_version "10.0")
	(general
		(thickness 1.6)
		(legacy_teardrops no)
	)
	(paper "A4")
	(title_block
		(title "Wiwynn_Tioga_Pass_MB.brd")
		(comment 1 "Tioga Pass / footprints 3904-3906 of 4770")
	)
	(layers
		(0 "F.Cu" signal "TOP")
		(4 "In1.Cu" signal "L2GND")
		(6 "In2.Cu" signal "L3")
		(8 "In3.Cu" signal "L4GND")
		(10 "In4.Cu" signal "L5")
		(12 "In5.Cu" signal "L6GND")
		(14 "In6.Cu" signal "L7VCC")
		(16 "In7.Cu" signal "L8VCC")
		(18 "In8.Cu" signal "L9GND")
		(20 "In9.Cu" signal "L10")
		(22 "In10.Cu" signal "L11GND")
		(24 "In11.Cu" signal "L12")
		(26 "In12.Cu" signal "L13GND")
		(2 "B.Cu" signal "BOTTOM")
		(9 "F.Adhes" user "F.Adhesive")
		(11 "B.Adhes" user "B.Adhesive")
		(13 "F.Paste" user "Package Geometry/Pastemask Top")
		(15 "B.Paste" user "Package Geometry/Pastemask Bottom")
		(5 "F.SilkS" user "Ref Des/Silkscreen Top")
		(7 "B.SilkS" user "Ref Des/Silkscreen Bottom")
		(1 "F.Mask" user "Board Geometry/Soldermask Top")
		(3 "B.Mask" user "Board Geometry/Soldermask Bottom")
		(17 "Dwgs.User" user "User.Drawings")
		(19 "Cmts.User" user "User.Comments")
		(21 "Eco1.User" user "User.Eco1")
		(23 "Eco2.User" user "User.Eco2")
		(25 "Edge.Cuts" user "Board Geometry/Outline")
		(27 "Margin" user)
		(31 "F.CrtYd" user "Package Geometry/Place Bound Top")
		(29 "B.CrtYd" user "Package Geometry/Place Bound Bottom")
		(35 "F.Fab" user "Ref Des/Assembly Top")
		(33 "B.Fab" user "Ref Des/Assembly Bottom")
	)
	(footprint ""
		(layer "B.Cu")
		(at 271.604486 -68.17614 180)
		(property "Reference" "C5P42"
			(at 0 0 0)
			(layer "B.SilkS")
			(hide yes)
			(effects
				(font
					(size 1.27 1.27)
				)
				(justify mirror)
			)
		)
		(property "Value" ""
			(at 0 0 0)
			(layer "B.Fab")
			(effects
				(font
					(size 1.27 1.27)
				)
				(justify mirror)
			)
		)
		(duplicate_pad_numbers_are_jumpers no)
		(fp_poly
			(pts
				(xy 0.7239 -0.2159) (xy -0.7239 -0.2159) (xy -0.7239 1.9939) (xy 0.7239 1.9939)
			)
			(stroke
				(width 0)
				(type default)
			)
			(fill no)
			(layer "B.CrtYd")
		)
		(fp_line
			(start 0.7239 1.9939)
			(end -0.7239 1.9939)
			(stroke
				(width 0.1)
				(type default)
			)
			(layer "B.Fab")
		)
		(fp_line
			(start 0.7239 -0.2159)
			(end 0.7239 1.9939)
			(stroke
				(width 0.1)
				(type default)
			)
			(layer "B.Fab")
		)
		(fp_line
			(start -0.7239 1.9939)
			(end -0.7239 -0.2159)
			(stroke
				(width 0.1)
				(type default)
			)
			(layer "B.Fab")
		)
		(fp_line
			(start -0.7239 -0.2159)
			(end 0.7239 -0.2159)
			(stroke
				(width 0.1)
				(type default)
			)
			(layer "B.Fab")
		)
		(pad "1" smd rect
			(at 0 0)
			(size 1.27 1.016)
			(layers "B.Cu" "B.Mask" "B.Paste")
			(net "PVDDQ_ABC")
		)
		(pad "2" smd rect
			(at 0 1.778)
			(size 1.27 1.016)
			(layers "B.Cu" "B.Mask" "B.Paste")
			(net "GND")
		)
		(zone
			(layer "B.Cu")
			(hatch none 0.5)
			(connect_pads
				(clearance 0)
			)
			(min_thickness 0.25)
			(keepout
				(tracks not_allowed)
				(vias allowed)
				(pads allowed)
				(copperpour not_allowed)
				(footprints allowed)
			)
			(placement
				(enabled no)
				(sheetname "")
			)
			(fill
				(thermal_gap 0.5)
				(thermal_bridge_width 0.5)
				(island_removal_mode 0)
			)
			(polygon
				(pts
					(xy 270.969486 -68.68414) (xy 272.239486 -68.68414) (xy 272.239486 -69.44614) (xy 270.969486 -69.44614)
				)
			)
		)
	)
	(footprint ""
		(layer "B.Cu")
		(at 348.794578 -99.966272 -90)
		(property "Reference" "R3N7"
			(at 0 0 90)
			(layer "B.SilkS")
			(hide yes)
			(effects
				(font
					(size 1.27 1.27)
				)
				(justify mirror)
			)
		)
		(property "Value" ""
			(at 0 0 90)
			(layer "B.Fab")
			(effects
				(font
					(size 1.27 1.27)
				)
				(justify mirror)
			)
		)
		(duplicate_pad_numbers_are_jumpers no)
		(fp_poly
			(pts
				(xy 0.2794 -0.1016) (xy -0.2794 -0.1016) (xy -0.2794 0.9906) (xy 0.2794 0.9906)
			)
			(stroke
				(width 0)
				(type default)
			)
			(fill no)
			(layer "B.CrtYd")
		)
		(fp_line
			(start -0.2794 0.9906)
			(end -0.2794 -0.1016)
			(stroke
				(width 0.1)
				(type default)
			)
			(layer "B.Fab")
		)
		(fp_line
			(start 0.2794 0.9906)
			(end -0.2794 0.9906)
			(stroke
				(width 0.1)
				(type default)
			)
			(layer "B.Fab")
		)
		(fp_line
			(start -0.2794 -0.1016)
			(end 0.2794 -0.1016)
			(stroke
				(width 0.1)
				(type default)
			)
			(layer "B.Fab")
		)
		(fp_line
			(start 0.2794 -0.1016)
			(end 0.2794 0.9906)
			(stroke
				(width 0.1)
				(type default)
			)
			(layer "B.Fab")
		)
		(pad "1" smd rect
			(at 0 0 90)
			(size 0.508 0.508)
			(layers "B.Cu" "B.Mask" "B.Paste")
			(net "VR_PVCCIO_CPU0_PH1_VCIN")
		)
		(pad "2" smd rect
			(at 0 0.889 90)
			(size 0.508 0.508)
			(layers "B.Cu" "B.Mask" "B.Paste")
			(net "P5V_STBY")
		)
		(zone
			(layer "B.Cu")
			(hatch none 0.5)
			(connect_pads
				(clearance 0)
			)
			(min_thickness 0.25)
			(keepout
				(tracks not_allowed)
				(vias allowed)
				(pads allowed)
				(copperpour not_allowed)
				(footprints allowed)
			)
			(placement
				(enabled no)
				(sheetname "")
			)
			(fill
				(thermal_gap 0.5)
				(thermal_bridge_width 0.5)
				(island_removal_mode 0)
			)
			(polygon
				(pts
					(xy 348.159578 -99.712272) (xy 348.159578 -100.220272) (xy 348.540578 -100.220272) (xy 348.540578 -99.712272)
				)
			)
		)
		(zone
			(layer "B.Cu")
			(hatch none 0.5)
			(connect_pads
				(clearance 0)
			)
			(min_thickness 0.25)
			(keepout
				(tracks allowed)
				(vias not_allowed)
				(pads allowed)
				(copperpour not_allowed)
				(footprints allowed)
			)
			(placement
				(enabled no)
				(sheetname "")
			)
			(fill
				(thermal_gap 0.5)
				(thermal_bridge_width 0.5)
				(island_removal_mode 0)
			)
			(polygon
				(pts
					(xy 348.540578 -99.712272) (xy 348.540578 -100.220272) (xy 348.159578 -100.220272) (xy 348.159578 -99.712272)
				)
			)
		)
	)
	(footprint ""
		(layer "B.Cu")
		(at 472.2368 -124.8791 90)
		(property "Reference" "R1M5"
			(at 0 0 90)
			(layer "B.SilkS")
			(hide yes)
			(effects
				(font
					(size 1.27 1.27)
				)
				(justify mirror)
			)
		)
		(property "Value" ""
			(at 0 0 90)
			(layer "B.Fab")
			(effects
				(font
					(size 1.27 1.27)
				)
				(justify mirror)
			)
		)
		(duplicate_pad_numbers_are_jumpers no)
		(fp_rect
			(start -0.2794 -0.1016)
			(end 0.2794 0.9906)
			(stroke
				(width 0)
				(type default)
			)
			(fill no)
			(layer "B.CrtYd")
		)
		(fp_line
			(start 0.2794 -0.1016)
			(end 0.2794 0.9906)
			(stroke
				(width 0.1)
				(type default)
			)
			(layer "B.Fab")
		)
		(fp_line
			(start -0.2794 -0.1016)
			(end 0.2794 -0.1016)
			(stroke
				(width 0.1)
				(type default)
			)
			(layer "B.Fab")
		)
		(fp_line
			(start 0.2794 0.9906)
			(end -0.2794 0.9906)
			(stroke
				(width 0.1)
				(type default)
			)
			(layer "B.Fab")
		)
		(fp_line
			(start -0.2794 0.9906)
			(end -0.2794 -0.1016)
			(stroke
				(width 0.1)
				(type default)
			)
			(layer "B.Fab")
		)
		(pad "1" smd rect
			(at 0 0 270)
			(size 0.508 0.508)
			(layers "B.Cu" "B.Mask" "B.Paste")
			(net "USB2_P01_DP")
		)
		(pad "2" smd rect
			(at 0 0.889 270)
			(size 0.508 0.508)
			(layers "B.Cu" "B.Mask" "B.Paste")
			(net "USB2_P01_ESD_DP")
		)
		(zone
			(layer "B.Cu")
			(hatch none 0.5)
			(connect_pads
				(clearance 0)
			)
			(min_thickness 0.25)
			(keepout
				(tracks allowed)
				(vias not_allowed)
				(pads allowed)
				(copperpour not_allowed)
				(footprints allowed)
			)
			(placement
				(enabled no)
				(sheetname "")
			)
			(fill
				(thermal_gap 0.5)
				(thermal_bridge_width 0.5)
				(island_removal_mode 0)
			)
			(polygon
				(pts
					(xy 472.4908 -124.6251) (xy 472.8718 -124.6251) (xy 472.8718 -125.1331) (xy 472.4908 -125.1331)
				)
			)
		)
	)
)
